# BASEBOARD_FAB2 (Tioga Pass) — schematic netlist excerpt (pin names and nets, part order shuffled) for the footprints in the layout excerpt that follows; sources: Cadence DE-HDL packaged netlist, KiCad conversion of Wiwynn_Tioga_Pass_MB.brd

RT36  RES  0 5.0% CHIP  pkg 0603  page 216 : A = VR_PVDDQ_ABC_PH2_BOOT ; B = VR_PVDDQ_ABC_PH2_BOOT_R
C10W4  CAP_A  0.1UF 16V 10% X7R  pkg 0402V  page 251 : A = P3V3_STBY ; B = GND
R8G16  RES  0.0 5% EMPTY  pkg 0402  page 189 : A = JTAG_PCH_PLD_TCK ; B = JTAG_TCK

(kicad_pcb
	(version 20260206)
	(generator "pcbnew")
	(generator_version "10.0")
	(general
		(thickness 1.6)
		(legacy_teardrops no)
	)
	(paper "A4")
	(title_block
		(title "Wiwynn_Tioga_Pass_MB.brd")
		(comment 1 "Tioga Pass / footprints 382-384 of 4770")
	)
	(layers
		(0 "F.Cu" signal "TOP")
		(4 "In1.Cu" signal "L2GND")
		(6 "In2.Cu" signal "L3")
		(8 "In3.Cu" signal "L4GND")
		(10 "In4.Cu" signal "L5")
		(12 "In5.Cu" signal "L6GND")
		(14 "In6.Cu" signal "L7VCC")
		(16 "In7.Cu" signal "L8VCC")
		(18 "In8.Cu" signal "L9GND")
		(20 "In9.Cu" signal "L10")
		(22 "In10.Cu" signal "L11GND")
		(24 "In11.Cu" signal "L12")
		(26 "In12.Cu" signal "L13GND")
		(2 "B.Cu" signal "BOTTOM")
		(9 "F.Adhes" user "F.Adhesive")
		(11 "B.Adhes" user "B.Adhesive")
		(13 "F.Paste" user "Package Geometry/Pastemask Top")
		(15 "B.Paste" user "Package Geometry/Pastemask Bottom")
		(5 "F.SilkS" user "Ref Des/Silkscreen Top")
		(7 "B.SilkS" user "Ref Des/Silkscreen Bottom")
		(1 "F.Mask" user "Board Geometry/Soldermask Top")
		(3 "B.Mask" user "Board Geometry/Soldermask Bottom")
		(17 "Dwgs.User" user "User.Drawings")
		(19 "Cmts.User" user "User.Comments")
		(21 "Eco1.User" user "User.Eco1")
		(23 "Eco2.User" user "User.Eco2")
		(25 "Edge.Cuts" user "Board Geometry/Outline")
		(27 "Margin" user)
		(31 "F.CrtYd" user "Package Geometry/Place Bound Top")
		(29 "B.CrtYd" user "Package Geometry/Place Bound Bottom")
		(35 "F.Fab" user "Ref Des/Assembly Top")
		(33 "B.Fab" user "Ref Des/Assembly Bottom")
	)
	(footprint ""
		(layer "F.Cu")
		(at 433.9336 -18.533872 -90)
		(property "Reference" "C10W4"
			(at -0.8382 -0.67818 270)
			(unlocked yes)
			(layer "F.SilkS")
			(effects
				(font
					(size 0.4064 0.254)
					(thickness 0.1524)
				)
				(justify left)
			)
		)
		(property "Value" ""
			(at 0 0 270)
			(layer "F.Fab")
			(effects
				(font
					(size 1.27 1.27)
				)
			)
		)
		(duplicate_pad_numbers_are_jumpers no)
		(fp_poly
			(pts
				(xy 0.3048 -0.1016) (xy 0.3048 0.9906) (xy -0.3048 0.9906) (xy -0.3048 -0.1016)
			)
			(stroke
				(width 0)
				(type default)
			)
			(fill no)
			(layer "F.CrtYd")
		)
		(fp_line
			(start -0.3048 0.9906)
			(end 0.3048 0.9906)
			(stroke
				(width 0.1)
				(type default)
			)
			(layer "F.Fab")
		)
		(fp_line
			(start 0.3048 0.9906)
			(end 0.3048 -0.1016)
			(stroke
				(width 0.1)
				(type default)
			)
			(layer "F.Fab")
		)
		(fp_line
			(start -0.3048 -0.1016)
			(end -0.3048 0.9906)
			(stroke
				(width 0.1)
				(type default)
			)
			(layer "F.Fab")
		)
		(fp_line
			(start 0.3048 -0.1016)
			(end -0.3048 -0.1016)
			(stroke
				(width 0.1)
				(type default)
			)
			(layer "F.Fab")
		)
		(pad "1" smd rect
			(at 0 0 270)
			(size 0.508 0.508)
			(layers "F.Cu" "F.Mask" "F.Paste")
			(net "P3V3_STBY")
		)
		(pad "2" smd rect
			(at 0 0.889 270)
			(size 0.508 0.508)
			(layers "F.Cu" "F.Mask" "F.Paste")
			(net "GND")
		)
		(zone
			(layer "F.Cu")
			(hatch none 0.5)
			(connect_pads
				(clearance 0)
			)
			(min_thickness 0.25)
			(keepout
				(tracks not_allowed)
				(vias allowed)
				(pads allowed)
				(copperpour not_allowed)
				(footprints allowed)
			)
			(placement
				(enabled no)
				(sheetname "")
			)
			(fill
				(thermal_gap 0.5)
				(thermal_bridge_width 0.5)
				(island_removal_mode 0)
			)
			(polygon
				(pts
					(xy 433.2986 -18.787872) (xy 433.2986 -18.279872) (xy 433.6796 -18.279872) (xy 433.6796 -18.787872)
				)
			)
		)
		(zone
			(layer "F.Cu")
			(hatch none 0.5)
			(connect_pads
				(clearance 0)
			)
			(min_thickness 0.25)
			(keepout
				(tracks allowed)
				(vias not_allowed)
				(pads allowed)
				(copperpour not_allowed)
				(footprints allowed)
			)
			(placement
				(enabled no)
				(sheetname "")
			)
			(fill
				(thermal_gap 0.5)
				(thermal_bridge_width 0.5)
				(island_removal_mode 0)
			)
			(polygon
				(pts
					(xy 433.6796 -18.787872) (xy 433.6796 -18.279872) (xy 433.2986 -18.279872) (xy 433.2986 -18.787872)
				)
			)
		)
	)
	(footprint ""
		(layer "F.Cu")
		(at 396.5448 -0.2286)
		(property "Reference" "R8G16"
			(at 0 0 0)
			(layer "F.SilkS")
			(hide yes)
			(effects
				(font
					(size 1.27 1.27)
				)
			)
		)
		(property "Value" ""
			(at 0 0 0)
			(layer "F.Fab")
			(effects
				(font
					(size 1.27 1.27)
				)
			)
		)
		(duplicate_pad_numbers_are_jumpers no)
		(fp_poly
			(pts
				(xy -0.2794 -0.1016) (xy 0.2794 -0.1016) (xy 0.2794 0.9906) (xy -0.2794 0.9906)
			)
			(stroke
				(width 0)
				(type default)
			)
			(fill no)
			(layer "F.CrtYd")
		)
		(fp_line
			(start -0.2794 -0.1016)
			(end -0.2794 0.9906)
			(stroke
				(width 0.1)
				(type default)
			)
			(layer "F.Fab")
		)
		(fp_line
			(start -0.2794 0.9906)
			(end 0.2794 0.9906)
			(stroke
				(width 0.1)
				(type default)
			)
			(layer "F.Fab")
		)
		(fp_line
			(start 0.2794 -0.1016)
			(end -0.2794 -0.1016)
			(stroke
				(width 0.1)
				(type default)
			)
			(layer "F.Fab")
		)
		(fp_line
			(start 0.2794 0.9906)
			(end 0.2794 -0.1016)
			(stroke
				(width 0.1)
				(type default)
			)
			(layer "F.Fab")
		)
		(pad "1" smd rect
			(at 0 0)
			(size 0.508 0.508)
			(layers "F.Cu" "F.Mask" "F.Paste")
			(net "JTAG_PCH_PLD_TCK")
		)
		(pad "2" smd rect
			(at 0 0.889)
			(size 0.508 0.508)
			(layers "F.Cu" "F.Mask" "F.Paste")
			(net "JTAG_TCK")
		)
		(zone
			(layer "F.Cu")
			(hatch none 0.5)
			(connect_pads
				(clearance 0)
			)
			(min_thickness 0.25)
			(keepout
				(tracks allowed)
				(vias not_allowed)
				(pads allowed)
				(copperpour not_allowed)
				(footprints allowed)
			)
			(placement
				(enabled no)
				(sheetname "")
			)
			(fill
				(thermal_gap 0.5)
				(thermal_bridge_width 0.5)
				(island_removal_mode 0)
			)
			(polygon
				(pts
					(xy 396.2908 0.0254) (xy 396.7988 0.0254) (xy 396.7988 0.4064) (xy 396.2908 0.4064)
				)
			)
		)
		(zone
			(layer "F.Cu")
			(hatch none 0.5)
			(connect_pads
				(clearance 0)
			)
			(min_thickness 0.25)
			(keepout
				(tracks not_allowed)
				(vias allowed)
				(pads allowed)
				(copperpour not_allowed)
				(footprints allowed)
			)
			(placement
				(enabled no)
				(sheetname "")
			)
			(fill
				(thermal_gap 0.5)
				(thermal_bridge_width 0.5)
				(island_removal_mode 0)
			)
			(polygon
				(pts
					(xy 396.2908 0.4064) (xy 396.7988 0.4064) (xy 396.7988 0.0254) (xy 396.2908 0.0254)
				)
			)
		)
	)
	(footprint ""
		(layer "F.Cu")
		(at 352.487738 2.51079 -90)
		(property "Reference" "RT36"
			(at 1.01473 0.656336 180)
			(unlocked yes)
			(layer "F.SilkS")
			(effects
				(font
					(size 0.4064 0.254)
					(thickness 0.1524)
				)
			)
		)
		(property "Value" ""
			(at 0 0 270)
			(layer "F.Fab")
			(effects
				(font
					(size 1.27 1.27)
				)
			)
		)
		(duplicate_pad_numbers_are_jumpers no)
		(fp_poly
			(pts
				(xy -0.4953 -0.2032) (xy 0.4953 -0.2032) (xy 0.4953 1.6002) (xy -0.4953 1.6002)
			)
			(stroke
				(width 0)
				(type default)
			)
			(fill no)
			(layer "F.CrtYd")
		)
		(fp_line
			(start -0.4953 1.6002)
			(end -0.4953 -0.2032)
			(stroke
				(width 0.1)
				(type default)
			)
			(layer "F.Fab")
		)
		(fp_line
			(start 0.4953 1.6002)
			(end -0.4953 1.6002)
			(stroke
				(width 0.1)
				(type default)
			)
			(layer "F.Fab")
		)
		(fp_line
			(start -0.4953 -0.2032)
			(end 0.4953 -0.2032)
			(stroke
				(width 0.1)
				(type default)
			)
			(layer "F.Fab")
		)
		(fp_line
			(start 0.4953 -0.2032)
			(end 0.4953 1.6002)
			(stroke
				(width 0.1)
				(type default)
			)
			(layer "F.Fab")
		)
		(pad "1" smd rect
			(at 0 0 270)
			(size 0.762 0.889)
			(layers "F.Cu" "F.Mask" "F.Paste")
			(net "VR_PVDDQ_ABC_PH2_BOOT")
		)
		(pad "2" smd rect
			(at 0 1.397 270)
			(size 0.762 0.889)
			(layers "F.Cu" "F.Mask" "F.Paste")
			(net "VR_PVDDQ_ABC_PH2_BOOT_R")
		)
		(zone
			(layer "F.Cu")
			(hatch none 0.5)
			(connect_pads
				(clearance 0)
			)
			(min_thickness 0.25)
			(keepout
				(tracks not_allowed)
				(vias allowed)
				(pads allowed)
				(copperpour not_allowed)
				(footprints allowed)
			)
			(placement
				(enabled no)
				(sheetname "")
			)
			(fill
				(thermal_gap 0.5)
				(thermal_bridge_width 0.5)
				(island_removal_mode 0)
			)
			(polygon
				(pts
					(xy 351.535238 2.12979) (xy 351.535238 2.89179) (xy 352.043238 2.89179) (xy 352.043238 2.12979)
				)
			)
		)
		(zone
			(layer "F.Cu")
			(hatch none 0.5)
			(connect_pads
				(clearance 0)
			)
			(min_thickness 0.25)
			(keepout
				(tracks allowed)
				(vias not_allowed)
				(pads allowed)
				(copperpour not_allowed)
				(footprints allowed)
			)
			(placement
				(enabled no)
				(sheetname "")
			)
			(fill
				(thermal_gap 0.5)
				(thermal_bridge_width 0.5)
				(island_removal_mode 0)
			)
			(polygon
				(pts
					(xy 351.535238 2.89179) (xy 352.043238 2.89179) (xy 352.043238 2.12979) (xy 351.535238 2.12979)
				)
			)
		)
	)
)
